(kicad_pcb
	(version 20260206)
	(generator "pcbnew")
	(generator_version "10.0")
	(general
		(thickness 1.21888)
		(legacy_teardrops no)
	)
	(paper "A4")
	(title_block
		(title "timecard-v9 — TimeCard-DC-V9_EXP.PcbDoc")
		(comment 1 "Time Appliance Project (Time Card) / footprints 364-377 of 402")
	)
	(layers
		(0 "F.Cu" signal "TOP")
		(4 "In1.Cu" signal "SGND")
		(6 "In2.Cu" signal "IN1")
		(8 "In3.Cu" signal "IN2")
		(10 "In4.Cu" signal "SGND1")
		(2 "B.Cu" signal "BOTTOM")
		(9 "F.Adhes" user "F.Adhesive")
		(11 "B.Adhes" user "B.Adhesive")
		(13 "F.Paste" user "Top Paste")
		(15 "B.Paste" user "Bottom Paste")
		(5 "F.SilkS" user "Top Overlay")
		(7 "B.SilkS" user "Bottom Overlay")
		(1 "F.Mask" user "Top Solder")
		(3 "B.Mask" user "Bottom Solder")
		(17 "Dwgs.User" user "User.Drawings")
		(19 "Cmts.User" user "User.Comments")
		(21 "Eco1.User" user "User.Eco1")
		(23 "Eco2.User" user "User.Eco2")
		(25 "Edge.Cuts" user)
		(27 "Margin" user)
		(31 "F.CrtYd" user "Top Courtyard")
		(29 "B.CrtYd" user "Bottom Courtyard")
		(35 "F.Fab" user "Top Component Center")
		(33 "B.Fab" user "Bottom Component Center")
	)
	(footprint "Vault:RESC1005X40X25ML05T10"
		(layer "B.Cu")
		(at 100.3216 61.1162 -90)
		(property "Reference" "R2"
			(at -0.7 1.106655 90)
			(unlocked yes)
			(layer "B.SilkS")
			(effects
				(font
					(size 0.762 0.762)
					(thickness 0.2286)
				)
				(justify left bottom mirror)
			)
		)
		(property "Value" "147K_1%_0402"
			(at 9.461245 17.0993 0)
			(unlocked yes)
			(layer "B.SilkS")
			(hide yes)
			(effects
				(font
					(size 0.762 0.762)
					(thickness 0.2286)
				)
				(justify left bottom mirror)
			)
		)
		(sheetname "03-POWER")
		(sheetfile "03-POWER.kicad_sch")
		(duplicate_pad_numbers_are_jumpers no)
		(pad "1" smd rect
			(at -0.475 0 180)
			(size 0.65 0.7)
			(layers "B.Cu" "B.Mask" "B.Paste")
			(net "P5V_MUN_FB")
		)
		(pad "2" smd rect
			(at 0.475 0 180)
			(size 0.65 0.7)
			(layers "B.Cu" "B.Mask" "B.Paste")
			(net "NetR2_2")
		)
	)
	(footprint "Vault:CAPC1005X55X25LL05T10"
		(layer "B.Cu")
		(at 225.2116 115.83602 180)
		(property "Reference" "C87"
			(at 0.3186 0.992889 0)
			(unlocked yes)
			(layer "B.SilkS")
			(effects
				(font
					(size 0.762 0.762)
					(thickness 0.2286)
				)
				(justify mirror)
			)
		)
		(property "Value" "47pF_50V_0402"
			(at -2.656031 -9.61078 90)
			(unlocked yes)
			(layer "B.SilkS")
			(hide yes)
			(effects
				(font
					(size 0.762 0.762)
					(thickness 0.2286)
				)
				(justify mirror)
			)
		)
		(sheetname "09-USBUart_PPSMUX_UARTMUX")
		(sheetfile "09-USBUart_PPSMUX_UARTMUX.kicad_sch")
		(duplicate_pad_numbers_are_jumpers no)
		(pad "1" smd rect
			(at -0.39 0 90)
			(size 0.52 0.56)
			(layers "B.Cu" "B.Mask" "B.Paste")
			(net "GND")
		)
		(pad "2" smd rect
			(at 0.39 0 90)
			(size 0.52 0.56)
			(layers "B.Cu" "B.Mask" "B.Paste")
			(net "FTDI_USB_R_P")
		)
	)
	(footprint "Vault:RESC1005X40X25LL05T05"
		(layer "B.Cu")
		(at 224.1216 75.8162 90)
		(property "Reference" "R64"
			(at 0.2286 1.173069 270)
			(unlocked yes)
			(layer "B.SilkS")
			(effects
				(font
					(size 0.762 0.762)
					(thickness 0.2286)
				)
				(justify mirror)
			)
		)
		(property "Value" "0_1%_0402"
			(at -2.579871 -6.66536 0)
			(unlocked yes)
			(layer "B.SilkS")
			(hide yes)
			(effects
				(font
					(size 0.762 0.762)
					(thickness 0.2286)
				)
				(justify mirror)
			)
		)
		(sheetname "03-POWER")
		(sheetfile "03-POWER.kicad_sch")
		(duplicate_pad_numbers_are_jumpers no)
		(pad "1" smd rect
			(at -0.4 0)
			(size 0.45 0.45)
			(layers "B.Cu" "B.Mask" "B.Paste")
			(net "NetR64_1")
		)
		(pad "2" smd rect
			(at 0.4 0)
			(size 0.45 0.45)
			(layers "B.Cu" "B.Mask" "B.Paste")
			(net "GND")
		)
	)
	(footprint "Vault:CAPC1608X87X45ML20T05"
		(layer "B.Cu")
		(at 128.0216 90.2162)
		(property "Reference" "C23"
			(at 0.2286 1.573069 180)
			(unlocked yes)
			(layer "B.SilkS")
			(effects
				(font
					(size 0.762 0.762)
					(thickness 0.2286)
				)
				(justify mirror)
			)
		)
		(property "Value" "0.1uF"
			(at 2.069035 -2.630671 180)
			(unlocked yes)
			(layer "B.SilkS")
			(hide yes)
			(effects
				(font
					(size 0.762 0.762)
					(thickness 0.2286)
				)
				(justify mirror)
			)
		)
		(sheetname "06-MAC")
		(sheetfile "06-MAC.kicad_sch")
		(duplicate_pad_numbers_are_jumpers no)
		(pad "1" smd rect
			(at -0.7 0 270)
			(size 1.1 1.05)
			(layers "B.Cu" "B.Mask" "B.Paste")
			(net "GND")
		)
		(pad "2" smd rect
			(at 0.7 0 270)
			(size 1.1 1.05)
			(layers "B.Cu" "B.Mask" "B.Paste")
			(net "+3.3V")
		)
	)
	(footprint "Vault:RESC1005X40X25NL10T10"
		(layer "B.Cu")
		(at 86.0716 56.5662)
		(property "Reference" "R6"
			(at 0.45 -0.517115 0)
			(unlocked yes)
			(layer "B.SilkS")
			(effects
				(font
					(size 0.762 0.762)
					(thickness 0.2286)
				)
				(justify left bottom mirror)
			)
		)
		(property "Value" "20K_1%_0402"
			(at 10.4447 -4.536755 0)
			(unlocked yes)
			(layer "B.SilkS")
			(hide yes)
			(effects
				(font
					(size 0.762 0.762)
					(thickness 0.2286)
				)
				(justify left bottom mirror)
			)
		)
		(sheetname "03-POWER")
		(sheetfile "03-POWER.kicad_sch")
		(duplicate_pad_numbers_are_jumpers no)
		(pad "1" smd rect
			(at -0.425 0 270)
			(size 0.6 0.65)
			(layers "B.Cu" "B.Mask" "B.Paste")
			(net "+12V")
		)
		(pad "2" smd rect
			(at 0.425 0 270)
			(size 0.6 0.65)
			(layers "B.Cu" "B.Mask" "B.Paste")
			(net "NetR6_2")
		)
	)
	(footprint "Vault:FP-0402-L_1_0_0_05-W_0_5-IPC_A"
		(layer "B.Cu")
		(at 219.66155 127.59915 -90)
		(property "Reference" "C111"
			(at 2.26305 -0.133119 270)
			(unlocked yes)
			(layer "B.SilkS")
			(effects
				(font
					(size 0.762 0.762)
					(thickness 0.254)
				)
				(justify mirror)
			)
		)
		(property "Value" "1uF_16V_0402"
			(at -2.744951 -8.315705 180)
			(unlocked yes)
			(layer "B.SilkS")
			(hide yes)
			(effects
				(font
					(size 0.762 0.762)
					(thickness 0.254)
				)
				(justify mirror)
			)
		)
		(sheetname "09-USBUart_PPSMUX_UARTMUX")
		(sheetfile "09-USBUart_PPSMUX_UARTMUX.kicad_sch")
		(duplicate_pad_numbers_are_jumpers no)
		(fp_line
			(start 0.83624 0.73624)
			(end -0.83623 0.73624)
			(stroke
				(width 0.2)
				(type solid)
			)
			(layer "B.SilkS")
		)
		(fp_line
			(start 0.83624 -0.73623)
			(end -0.83623 -0.73623)
			(stroke
				(width 0.2)
				(type solid)
			)
			(layer "B.SilkS")
		)
		(fp_line
			(start -1.03623 0.53624)
			(end -1.03623 -0.53624)
			(stroke
				(width 0.2)
				(type solid)
			)
			(layer "B.CrtYd")
		)
		(fp_line
			(start 1.03624 0.53624)
			(end -1.03623 0.53624)
			(stroke
				(width 0.2)
				(type solid)
			)
			(layer "B.CrtYd")
		)
		(fp_line
			(start 1.03624 0.53624)
			(end 1.03624 -0.53624)
			(stroke
				(width 0.2)
				(type solid)
			)
			(layer "B.CrtYd")
		)
		(fp_line
			(start 1.03624 -0.53624)
			(end -1.03623 -0.53624)
			(stroke
				(width 0.2)
				(type solid)
			)
			(layer "B.CrtYd")
		)
		(fp_line
			(start -1.03623 0.53624)
			(end -1.03623 -0.53624)
			(stroke
				(width 0.2)
				(type solid)
			)
			(layer "B.Fab")
		)
		(fp_line
			(start 1.03624 0.53624)
			(end -1.03623 0.53624)
			(stroke
				(width 0.2)
				(type solid)
			)
			(layer "B.Fab")
		)
		(fp_line
			(start 1.03624 0.53624)
			(end 1.03624 -0.53624)
			(stroke
				(width 0.2)
				(type solid)
			)
			(layer "B.Fab")
		)
		(fp_line
			(start 0 0.5)
			(end 0 -0.5)
			(stroke
				(width 0.1)
				(type solid)
			)
			(layer "B.Fab")
		)
		(fp_line
			(start 0.5 0)
			(end -0.5 0)
			(stroke
				(width 0.1)
				(type solid)
			)
			(layer "B.Fab")
		)
		(fp_line
			(start 1.03624 -0.53624)
			(end -1.03623 -0.53624)
			(stroke
				(width 0.2)
				(type solid)
			)
			(layer "B.Fab")
		)
		(fp_text user "${REFERENCE}"
			(at -0.00001 -0.09601 90)
			(unlocked yes)
			(layer "B.Fab")
			(effects
				(font
					(face "Arial")
					(size 0.63 0.63)
					(thickness 0.1)
				)
				(justify left bottom mirror)
			)
		)
		(pad "1" smd rect
			(at -0.47856 0 270)
			(size 0.71535 0.67248)
			(layers "B.Cu" "B.Mask" "B.Paste")
			(net "FTDI_P3V3")
			(solder_mask_margin 0)
			(solder_paste_margin 0)
		)
		(pad "2" smd rect
			(at 0.47857 0 270)
			(size 0.71535 0.67248)
			(layers "B.Cu" "B.Mask" "B.Paste")
			(net "GND")
			(solder_mask_margin 0)
			(solder_paste_margin 0)
		)
	)
	(footprint "Vault:FP-MK212BG-MFG"
		(layer "B.Cu")
		(at 207.5592 134.4334)
		(property "Reference" "C34"
			(at 0.17115 1.355879 180)
			(unlocked yes)
			(layer "B.SilkS")
			(effects
				(font
					(size 0.762 0.762)
					(thickness 0.2286)
				)
				(justify mirror)
			)
		)
		(property "Value" "10uF"
			(at -3.240271 -2.22164 270)
			(unlocked yes)
			(layer "B.SilkS")
			(hide yes)
			(effects
				(font
					(size 0.762 0.762)
					(thickness 0.2286)
				)
				(justify mirror)
			)
		)
		(sheetname "05-GPS_IMU_SENSORS")
		(sheetfile "05-GPS_IMU_SENSORS.kicad_sch")
		(duplicate_pad_numbers_are_jumpers no)
		(fp_line
			(start -0.125 -0.725)
			(end 0.125 -0.725)
			(stroke
				(width 0.2)
				(type solid)
			)
			(layer "B.SilkS")
		)
		(fp_line
			(start -0.125 0.725)
			(end 0.125 0.725)
			(stroke
				(width 0.2)
				(type solid)
			)
			(layer "B.SilkS")
		)
		(fp_line
			(start -1.6 -0.825)
			(end 1.6 -0.825)
			(stroke
				(width 0.2)
				(type solid)
			)
			(layer "B.CrtYd")
		)
		(fp_line
			(start -1.6 0.825)
			(end -1.6 -0.825)
			(stroke
				(width 0.2)
				(type solid)
			)
			(layer "B.CrtYd")
		)
		(fp_line
			(start -1.6 0.825)
			(end 1.6 0.825)
			(stroke
				(width 0.2)
				(type solid)
			)
			(layer "B.CrtYd")
		)
		(fp_line
			(start 1.6 0.825)
			(end 1.6 -0.825)
			(stroke
				(width 0.2)
				(type solid)
			)
			(layer "B.CrtYd")
		)
		(fp_line
			(start -1.6 -0.825)
			(end 1.6 -0.825)
			(stroke
				(width 0.2)
				(type solid)
			)
			(layer "B.Fab")
		)
		(fp_line
			(start -1.6 0.825)
			(end -1.6 -0.825)
			(stroke
				(width 0.2)
				(type solid)
			)
			(layer "B.Fab")
		)
		(fp_line
			(start -1.6 0.825)
			(end 1.6 0.825)
			(stroke
				(width 0.2)
				(type solid)
			)
			(layer "B.Fab")
		)
		(fp_line
			(start -0.5 0)
			(end 0.5 0)
			(stroke
				(width 0.1)
				(type solid)
			)
			(layer "B.Fab")
		)
		(fp_line
			(start 0 0.5)
			(end 0 -0.5)
			(stroke
				(width 0.1)
				(type solid)
			)
			(layer "B.Fab")
		)
		(fp_line
			(start 1.6 0.825)
			(end 1.6 -0.825)
			(stroke
				(width 0.2)
				(type solid)
			)
			(layer "B.Fab")
		)
		(fp_text user "${REFERENCE}"
			(at -0.00001 -0.09601 180)
			(unlocked yes)
			(layer "B.Fab")
			(effects
				(font
					(face "Arial")
					(size 0.63 0.63)
					(thickness 0.1)
				)
				(justify left bottom mirror)
			)
		)
		(pad "1" smd rect
			(at -1 0)
			(size 1 1.25)
			(layers "B.Cu" "B.Mask" "B.Paste")
			(net "GNSS2_P3V3")
			(solder_mask_margin 0)
			(solder_paste_margin 0)
		)
		(pad "2" smd rect
			(at 1 0)
			(size 1 1.25)
			(layers "B.Cu" "B.Mask" "B.Paste")
			(net "GND")
			(solder_mask_margin 0)
			(solder_paste_margin 0)
		)
	)
	(footprint "Vault:CAPC1608X87X45ML20T05"
		(layer "B.Cu")
		(at 215.9216 136.2162 180)
		(property "Reference" "C57"
			(at -0.2286 -1.173069 180)
			(unlocked yes)
			(layer "B.SilkS")
			(effects
				(font
					(size 0.762 0.762)
					(thickness 0.2286)
				)
				(justify mirror)
			)
		)
		(property "Value" "0.1uF"
			(at 2.069035 -2.630671 0)
			(unlocked yes)
			(layer "B.SilkS")
			(hide yes)
			(effects
				(font
					(size 0.762 0.762)
					(thickness 0.2286)
				)
				(justify mirror)
			)
		)
		(sheetname "05-GPS_IMU_SENSORS")
		(sheetfile "05-GPS_IMU_SENSORS.kicad_sch")
		(duplicate_pad_numbers_are_jumpers no)
		(pad "1" smd rect
			(at -0.7 0 90)
			(size 1.1 1.05)
			(layers "B.Cu" "B.Mask" "B.Paste")
			(net "GND")
		)
		(pad "2" smd rect
			(at 0.7 0 90)
			(size 1.1 1.05)
			(layers "B.Cu" "B.Mask" "B.Paste")
			(net "GNSS2_P3V3")
		)
	)
	(footprint "Vault:RESC1005X40X25LL05T10"
		(layer "B.Cu")
		(at 220.4216 109.5162)
		(property "Reference" "R78"
			(at -2.3286 0.126931 0)
			(unlocked yes)
			(layer "B.SilkS")
			(effects
				(font
					(size 0.762 0.762)
					(thickness 0.2286)
				)
				(justify mirror)
			)
		)
		(property "Value" "10K_1%_0402"
			(at -2.884671 -8.036475 270)
			(unlocked yes)
			(layer "B.SilkS")
			(hide yes)
			(effects
				(font
					(size 0.762 0.762)
					(thickness 0.2286)
				)
				(justify mirror)
			)
		)
		(sheetname "08-DIPSwitches_I2C")
		(sheetfile "08-DIPSwitches_I2C.kicad_sch")
		(duplicate_pad_numbers_are_jumpers no)
		(pad "1" smd rect
			(at -0.375 0 270)
			(size 0.45 0.5)
			(layers "B.Cu" "B.Mask" "B.Paste")
			(net "+3.3V")
		)
		(pad "2" smd rect
			(at 0.375 0 270)
			(size 0.45 0.5)
			(layers "B.Cu" "B.Mask" "B.Paste")
			(net "DIP_SW_UART_SEL")
		)
	)
	(footprint "Vault:RESC1005X40X25LL05T05"
		(layer "B.Cu")
		(at 100.2216 62.8162 180)
		(property "Reference" "R3"
			(at 1.1 -0.493345 0)
			(unlocked yes)
			(layer "B.SilkS")
			(effects
				(font
					(size 0.762 0.762)
					(thickness 0.2286)
				)
				(justify left bottom mirror)
			)
		)
		(property "Value" "0_1%_0402"
			(at 26.9821 -21.663245 0)
			(unlocked yes)
			(layer "B.SilkS")
			(hide yes)
			(effects
				(font
					(size 0.762 0.762)
					(thickness 0.2286)
				)
				(justify left bottom mirror)
			)
		)
		(sheetname "03-POWER")
		(sheetfile "03-POWER.kicad_sch")
		(duplicate_pad_numbers_are_jumpers no)
		(pad "1" smd rect
			(at -0.4 0 90)
			(size 0.45 0.45)
			(layers "B.Cu" "B.Mask" "B.Paste")
			(net "NetR2_2")
		)
		(pad "2" smd rect
			(at 0.4 0 90)
			(size 0.45 0.45)
			(layers "B.Cu" "B.Mask" "B.Paste")
			(net "P5V_SENSE")
		)
	)
	(footprint "Capacitors:CAPC1005X06N"
		(layer "B.Cu")
		(at 124.5576 151.7886 90)
		(property "Reference" "C44"
			(at 2.885 -1.204345 270)
			(unlocked yes)
			(layer "B.SilkS")
			(effects
				(font
					(size 0.762 0.762)
					(thickness 0.2286)
				)
				(justify left bottom mirror)
			)
		)
		(property "Value" "CAP_0402_0.1UF_50V"
			(at -3.382645 0.2921 0)
			(unlocked yes)
			(layer "B.SilkS")
			(hide yes)
			(effects
				(font
					(size 0.762 0.762)
					(thickness 0.2286)
				)
				(justify left bottom mirror)
			)
		)
		(sheetname "04-PCIe_JTAG")
		(sheetfile "04-PCIe_JTAG.kicad_sch")
		(duplicate_pad_numbers_are_jumpers no)
		(pad "1" smd rect
			(at -0.43 0)
			(size 0.64 0.68)
			(layers "B.Cu" "B.Mask" "B.Paste")
			(net "NetC44_1")
		)
		(pad "2" smd rect
			(at 0.43 0)
			(size 0.64 0.68)
			(layers "B.Cu" "B.Mask" "B.Paste")
			(net "PCIE_CLK_P")
		)
	)
	(footprint "Vault:FP-MK212BG-MFG"
		(layer "B.Cu")
		(at 215.9216 133.8162)
		(property "Reference" "C55"
			(at -0.2286 -1.673069 0)
			(unlocked yes)
			(layer "B.SilkS")
			(effects
				(font
					(size 0.762 0.762)
					(thickness 0.2286)
				)
				(justify mirror)
			)
		)
		(property "Value" "10uF"
			(at -3.240271 -2.22164 270)
			(unlocked yes)
			(layer "B.SilkS")
			(hide yes)
			(effects
				(font
					(size 0.762 0.762)
					(thickness 0.2286)
				)
				(justify mirror)
			)
		)
		(sheetname "05-GPS_IMU_SENSORS")
		(sheetfile "05-GPS_IMU_SENSORS.kicad_sch")
		(duplicate_pad_numbers_are_jumpers no)
		(fp_line
			(start -0.125 -0.725)
			(end 0.125 -0.725)
			(stroke
				(width 0.2)
				(type solid)
			)
			(layer "B.SilkS")
		)
		(fp_line
			(start -0.125 0.725)
			(end 0.125 0.725)
			(stroke
				(width 0.2)
				(type solid)
			)
			(layer "B.SilkS")
		)
		(fp_line
			(start -1.6 -0.825)
			(end 1.6 -0.825)
			(stroke
				(width 0.2)
				(type solid)
			)
			(layer "B.CrtYd")
		)
		(fp_line
			(start -1.6 0.825)
			(end -1.6 -0.825)
			(stroke
				(width 0.2)
				(type solid)
			)
			(layer "B.CrtYd")
		)
		(fp_line
			(start -1.6 0.825)
			(end 1.6 0.825)
			(stroke
				(width 0.2)
				(type solid)
			)
			(layer "B.CrtYd")
		)
		(fp_line
			(start 1.6 0.825)
			(end 1.6 -0.825)
			(stroke
				(width 0.2)
				(type solid)
			)
			(layer "B.CrtYd")
		)
		(fp_line
			(start -1.6 -0.825)
			(end 1.6 -0.825)
			(stroke
				(width 0.2)
				(type solid)
			)
			(layer "B.Fab")
		)
		(fp_line
			(start -1.6 0.825)
			(end -1.6 -0.825)
			(stroke
				(width 0.2)
				(type solid)
			)
			(layer "B.Fab")
		)
		(fp_line
			(start -1.6 0.825)
			(end 1.6 0.825)
			(stroke
				(width 0.2)
				(type solid)
			)
			(layer "B.Fab")
		)
		(fp_line
			(start -0.5 0)
			(end 0.5 0)
			(stroke
				(width 0.1)
				(type solid)
			)
			(layer "B.Fab")
		)
		(fp_line
			(start 0 0.5)
			(end 0 -0.5)
			(stroke
				(width 0.1)
				(type solid)
			)
			(layer "B.Fab")
		)
		(fp_line
			(start 1.6 0.825)
			(end 1.6 -0.825)
			(stroke
				(width 0.2)
				(type solid)
			)
			(layer "B.Fab")
		)
		(fp_text user "${REFERENCE}"
			(at -0.00002 -0.09601 180)
			(unlocked yes)
			(layer "B.Fab")
			(effects
				(font
					(face "Arial")
					(size 0.63 0.63)
					(thickness 0.1)
				)
				(justify left bottom mirror)
			)
		)
		(pad "1" smd rect
			(at -1 0)
			(size 1 1.25)
			(layers "B.Cu" "B.Mask" "B.Paste")
			(net "GNSS2_P3V3")
			(solder_mask_margin 0)
			(solder_paste_margin 0)
		)
		(pad "2" smd rect
			(at 1 0)
			(size 1 1.25)
			(layers "B.Cu" "B.Mask" "B.Paste")
			(net "GND")
			(solder_mask_margin 0)
			(solder_paste_margin 0)
		)
	)
	(footprint "Vault:RESC1005X40X25LL05T05"
		(layer "B.Cu")
		(at 83.5116 67.39847)
		(property "Reference" "R65"
			(at -0.3186 0.944651 0)
			(unlocked yes)
			(layer "B.SilkS")
			(effects
				(font
					(size 0.762 0.762)
					(thickness 0.2286)
				)
				(justify mirror)
			)
		)
		(property "Value" "0_1%_0402"
			(at -2.579871 -6.66537 270)
			(unlocked yes)
			(layer "B.SilkS")
			(hide yes)
			(effects
				(font
					(size 0.762 0.762)
					(thickness 0.2286)
				)
				(justify mirror)
			)
		)
		(sheetname "03-POWER")
		(sheetfile "03-POWER.kicad_sch")
		(duplicate_pad_numbers_are_jumpers no)
		(pad "1" smd rect
			(at -0.4 0 270)
			(size 0.45 0.45)
			(layers "B.Cu" "B.Mask" "B.Paste")
			(net "NetR65_1")
		)
		(pad "2" smd rect
			(at 0.4 0 270)
			(size 0.45 0.45)
			(layers "B.Cu" "B.Mask" "B.Paste")
			(net "+3.3V")
		)
	)
	(footprint "Vault:RESC1005X40X25LL05T05"
		(layer "B.Cu")
		(at 111.88072 89.9662)
		(property "Reference" "R56"
			(at 0.36948 7.423069 180)
			(unlocked yes)
			(layer "B.SilkS")
			(effects
				(font
					(size 0.762 0.762)
					(thickness 0.2286)
				)
				(justify mirror)
			)
		)
		(property "Value" "DNI_4.7K_0402"
			(at -3.151351 -5.29409 270)
			(unlocked yes)
			(layer "B.SilkS")
			(hide yes)
			(effects
				(font
					(size 0.762 0.762)
					(thickness 0.2286)
				)
				(justify mirror)
			)
		)
		(sheetname "05-GPS_IMU_SENSORS")
		(sheetfile "05-GPS_IMU_SENSORS.kicad_sch")
		(duplicate_pad_numbers_are_jumpers no)
		(pad "1" smd rect
			(at -0.4 0 270)
			(size 0.45 0.45)
			(layers "B.Cu" "B.Mask" "B.Paste")
			(net "GND")
		)
		(pad "2" smd rect
			(at 0.4 0 270)
			(size 0.45 0.45)
			(layers "B.Cu" "B.Mask" "B.Paste")
			(net "NetR53_1")
		)
	)
)
